(kicad_pcb
	(version 20260206)
	(generator "pcbnew")
	(generator_version "10.0")
	(general
		(thickness 1.6)
		(legacy_teardrops no)
	)
	(paper "A4")
	(title_block
		(title "03242023_DA0F0TMBIJ0_F0T_Motherboard_J_brd_V01_OCP.brd")
		(comment 1 "Grand Teton / footprints 1418-1424 of 6105")
	)
	(layers
		(0 "F.Cu" signal "TOP")
		(4 "In1.Cu" signal "GND")
		(6 "In2.Cu" signal "IN1")
		(8 "In3.Cu" signal "GND1")
		(10 "In4.Cu" signal "IN2")
		(12 "In5.Cu" signal "GND2")
		(14 "In6.Cu" signal "IN3")
		(16 "In7.Cu" signal "GND3")
		(18 "In8.Cu" signal "VCC")
		(20 "In9.Cu" signal "VCC1")
		(22 "In10.Cu" signal "GND4")
		(24 "In11.Cu" signal "IN4")
		(26 "In12.Cu" signal "GND5")
		(28 "In13.Cu" signal "IN5")
		(30 "In14.Cu" signal "GND6")
		(32 "In15.Cu" signal "IN6")
		(34 "In16.Cu" signal "GND7")
		(2 "B.Cu" signal "BOTTOM")
		(9 "F.Adhes" user "F.Adhesive")
		(11 "B.Adhes" user "B.Adhesive")
		(13 "F.Paste" user "Package Geometry/Pastemask Top")
		(15 "B.Paste" user "Package Geometry/Pastemask Bottom")
		(5 "F.SilkS" user "Ref Des/Silkscreen Top")
		(7 "B.SilkS" user "Ref Des/Silkscreen Bottom")
		(1 "F.Mask" user "Board Geometry/Soldermask Top")
		(3 "B.Mask" user "Board Geometry/Soldermask Bottom")
		(17 "Dwgs.User" user "User.Drawings")
		(19 "Cmts.User" user "User.Comments")
		(21 "Eco1.User" user "User.Eco1")
		(23 "Eco2.User" user "User.Eco2")
		(25 "Edge.Cuts" user "Board Geometry/Outline")
		(27 "Margin" user)
		(31 "F.CrtYd" user "Package Geometry/Place Bound Top")
		(29 "B.CrtYd" user "Package Geometry/Place Bound Bottom")
		(35 "F.Fab" user "Ref Des/Assembly Top")
		(33 "B.Fab" user "Ref Des/Assembly Bottom")
	)
	(footprint ""
		(layer "F.Cu")
		(at 315.110622 -53.203348 180)
		(property "Reference" "R372"
			(at 0 0 180)
			(layer "F.SilkS")
			(hide yes)
			(effects
				(font
					(size 1.27 1.27)
				)
			)
		)
		(property "Value" ""
			(at 0 0 180)
			(layer "F.Fab")
			(effects
				(font
					(size 1.27 1.27)
				)
			)
		)
		(duplicate_pad_numbers_are_jumpers no)
		(fp_line
			(start 0.7874 0.4064)
			(end -0.7874 0.4064)
			(stroke
				(width 0.1524)
				(type default)
			)
			(layer "F.SilkS")
		)
		(fp_line
			(start 0.7874 -0.4064)
			(end 0.7874 0.4064)
			(stroke
				(width 0.1524)
				(type default)
			)
			(layer "F.SilkS")
		)
		(fp_line
			(start -0.7874 0.4064)
			(end -0.7874 -0.4064)
			(stroke
				(width 0.1524)
				(type default)
			)
			(layer "F.SilkS")
		)
		(fp_line
			(start -0.7874 -0.4064)
			(end 0.7874 -0.4064)
			(stroke
				(width 0.1524)
				(type default)
			)
			(layer "F.SilkS")
		)
		(fp_line
			(start 0.67945 0.3048)
			(end 0.120396 0.3048)
			(stroke
				(width 0.1)
				(type default)
			)
			(layer "F.Fab")
		)
		(fp_line
			(start 0.67945 -0.3048)
			(end 0.67945 0.3048)
			(stroke
				(width 0.1)
				(type default)
			)
			(layer "F.Fab")
		)
		(fp_line
			(start 0.12065 -0.2794)
			(end 0.12065 -0.3048)
			(stroke
				(width 0.1)
				(type default)
			)
			(layer "F.Fab")
		)
		(fp_line
			(start 0.12065 -0.3048)
			(end 0.67945 -0.3048)
			(stroke
				(width 0.1)
				(type default)
			)
			(layer "F.Fab")
		)
		(fp_line
			(start 0.120396 0.3048)
			(end 0.120396 0.2794)
			(stroke
				(width 0.1)
				(type default)
			)
			(layer "F.Fab")
		)
		(fp_line
			(start 0.120396 0.2794)
			(end -0.12065 0.2794)
			(stroke
				(width 0.1)
				(type default)
			)
			(layer "F.Fab")
		)
		(fp_line
			(start -0.12065 0.3048)
			(end -0.67945 0.3048)
			(stroke
				(width 0.1)
				(type default)
			)
			(layer "F.Fab")
		)
		(fp_line
			(start -0.12065 0.2794)
			(end -0.12065 0.3048)
			(stroke
				(width 0.1)
				(type default)
			)
			(layer "F.Fab")
		)
		(fp_line
			(start -0.12065 -0.2794)
			(end 0.12065 -0.2794)
			(stroke
				(width 0.1)
				(type default)
			)
			(layer "F.Fab")
		)
		(fp_line
			(start -0.12065 -0.305054)
			(end -0.12065 -0.2794)
			(stroke
				(width 0.1)
				(type default)
			)
			(layer "F.Fab")
		)
		(fp_line
			(start -0.67945 0.3048)
			(end -0.67945 -0.305054)
			(stroke
				(width 0.1)
				(type default)
			)
			(layer "F.Fab")
		)
		(fp_line
			(start -0.67945 -0.305054)
			(end -0.12065 -0.305054)
			(stroke
				(width 0.1)
				(type default)
			)
			(layer "F.Fab")
		)
		(pad "1" smd circle
			(at -0.40005 0 180)
			(size 0 0)
			(layers "F.Cu" "F.Mask" "F.Paste")
			(net "FM_PCH_BOOT_BIOS_STRAP")
		)
		(pad "2" smd circle
			(at 0.40005 0 180)
			(size 0 0)
			(layers "F.Cu" "F.Mask" "F.Paste")
			(net "GND")
		)
	)
	(footprint ""
		(layer "F.Cu")
		(at 221.67088 -43.525948 180)
		(property "Reference" "R3530"
			(at 0 0 180)
			(layer "F.SilkS")
			(hide yes)
			(effects
				(font
					(size 1.27 1.27)
				)
			)
		)
		(property "Value" ""
			(at 0 0 180)
			(layer "F.Fab")
			(effects
				(font
					(size 1.27 1.27)
				)
			)
		)
		(duplicate_pad_numbers_are_jumpers no)
		(fp_line
			(start 0.7874 0.4064)
			(end -0.7874 0.4064)
			(stroke
				(width 0.1524)
				(type default)
			)
			(layer "F.SilkS")
		)
		(fp_line
			(start 0.7874 -0.4064)
			(end 0.7874 0.4064)
			(stroke
				(width 0.1524)
				(type default)
			)
			(layer "F.SilkS")
		)
		(fp_line
			(start -0.7874 0.4064)
			(end -0.7874 -0.4064)
			(stroke
				(width 0.1524)
				(type default)
			)
			(layer "F.SilkS")
		)
		(fp_line
			(start -0.7874 -0.4064)
			(end 0.7874 -0.4064)
			(stroke
				(width 0.1524)
				(type default)
			)
			(layer "F.SilkS")
		)
		(fp_line
			(start 0.67945 0.3048)
			(end 0.120396 0.3048)
			(stroke
				(width 0.1)
				(type default)
			)
			(layer "F.Fab")
		)
		(fp_line
			(start 0.67945 -0.3048)
			(end 0.67945 0.3048)
			(stroke
				(width 0.1)
				(type default)
			)
			(layer "F.Fab")
		)
		(fp_line
			(start 0.12065 -0.2794)
			(end 0.12065 -0.3048)
			(stroke
				(width 0.1)
				(type default)
			)
			(layer "F.Fab")
		)
		(fp_line
			(start 0.12065 -0.3048)
			(end 0.67945 -0.3048)
			(stroke
				(width 0.1)
				(type default)
			)
			(layer "F.Fab")
		)
		(fp_line
			(start 0.120396 0.3048)
			(end 0.120396 0.2794)
			(stroke
				(width 0.1)
				(type default)
			)
			(layer "F.Fab")
		)
		(fp_line
			(start 0.120396 0.2794)
			(end -0.12065 0.2794)
			(stroke
				(width 0.1)
				(type default)
			)
			(layer "F.Fab")
		)
		(fp_line
			(start -0.12065 0.3048)
			(end -0.67945 0.3048)
			(stroke
				(width 0.1)
				(type default)
			)
			(layer "F.Fab")
		)
		(fp_line
			(start -0.12065 0.2794)
			(end -0.12065 0.3048)
			(stroke
				(width 0.1)
				(type default)
			)
			(layer "F.Fab")
		)
		(fp_line
			(start -0.12065 -0.2794)
			(end 0.12065 -0.2794)
			(stroke
				(width 0.1)
				(type default)
			)
			(layer "F.Fab")
		)
		(fp_line
			(start -0.12065 -0.305054)
			(end -0.12065 -0.2794)
			(stroke
				(width 0.1)
				(type default)
			)
			(layer "F.Fab")
		)
		(fp_line
			(start -0.67945 0.3048)
			(end -0.67945 -0.305054)
			(stroke
				(width 0.1)
				(type default)
			)
			(layer "F.Fab")
		)
		(fp_line
			(start -0.67945 -0.305054)
			(end -0.12065 -0.305054)
			(stroke
				(width 0.1)
				(type default)
			)
			(layer "F.Fab")
		)
		(pad "1" smd circle
			(at -0.40005 0 180)
			(size 0 0)
			(layers "F.Cu" "F.Mask" "F.Paste")
			(net "P3V3_E1S_0")
		)
		(pad "2" smd circle
			(at 0.40005 0 180)
			(size 0 0)
			(layers "F.Cu" "F.Mask" "F.Paste")
			(net "SMB_E1S_3V3AUX_ISO_SCL_R")
		)
	)
	(footprint ""
		(layer "F.Cu")
		(at 120.37822 -419.415468)
		(property "Reference" "R3315"
			(at 0 0 0)
			(layer "F.SilkS")
			(hide yes)
			(effects
				(font
					(size 1.27 1.27)
				)
			)
		)
		(property "Value" ""
			(at 0 0 0)
			(layer "F.Fab")
			(effects
				(font
					(size 1.27 1.27)
				)
			)
		)
		(duplicate_pad_numbers_are_jumpers no)
		(fp_line
			(start -0.7874 -0.4064)
			(end 0.7874 -0.4064)
			(stroke
				(width 0.1524)
				(type default)
			)
			(layer "F.SilkS")
		)
		(fp_line
			(start -0.7874 0.4064)
			(end -0.7874 -0.4064)
			(stroke
				(width 0.1524)
				(type default)
			)
			(layer "F.SilkS")
		)
		(fp_line
			(start 0.7874 -0.4064)
			(end 0.7874 0.4064)
			(stroke
				(width 0.1524)
				(type default)
			)
			(layer "F.SilkS")
		)
		(fp_line
			(start 0.7874 0.4064)
			(end -0.7874 0.4064)
			(stroke
				(width 0.1524)
				(type default)
			)
			(layer "F.SilkS")
		)
		(fp_line
			(start -0.67945 -0.305054)
			(end -0.12065 -0.305054)
			(stroke
				(width 0.1)
				(type default)
			)
			(layer "F.Fab")
		)
		(fp_line
			(start -0.67945 0.3048)
			(end -0.67945 -0.305054)
			(stroke
				(width 0.1)
				(type default)
			)
			(layer "F.Fab")
		)
		(fp_line
			(start -0.12065 -0.305054)
			(end -0.12065 -0.2794)
			(stroke
				(width 0.1)
				(type default)
			)
			(layer "F.Fab")
		)
		(fp_line
			(start -0.12065 -0.2794)
			(end 0.12065 -0.2794)
			(stroke
				(width 0.1)
				(type default)
			)
			(layer "F.Fab")
		)
		(fp_line
			(start -0.12065 0.2794)
			(end -0.12065 0.3048)
			(stroke
				(width 0.1)
				(type default)
			)
			(layer "F.Fab")
		)
		(fp_line
			(start -0.12065 0.3048)
			(end -0.67945 0.3048)
			(stroke
				(width 0.1)
				(type default)
			)
			(layer "F.Fab")
		)
		(fp_line
			(start 0.120396 0.2794)
			(end -0.12065 0.2794)
			(stroke
				(width 0.1)
				(type default)
			)
			(layer "F.Fab")
		)
		(fp_line
			(start 0.120396 0.3048)
			(end 0.120396 0.2794)
			(stroke
				(width 0.1)
				(type default)
			)
			(layer "F.Fab")
		)
		(fp_line
			(start 0.12065 -0.3048)
			(end 0.67945 -0.3048)
			(stroke
				(width 0.1)
				(type default)
			)
			(layer "F.Fab")
		)
		(fp_line
			(start 0.12065 -0.2794)
			(end 0.12065 -0.3048)
			(stroke
				(width 0.1)
				(type default)
			)
			(layer "F.Fab")
		)
		(fp_line
			(start 0.67945 -0.3048)
			(end 0.67945 0.3048)
			(stroke
				(width 0.1)
				(type default)
			)
			(layer "F.Fab")
		)
		(fp_line
			(start 0.67945 0.3048)
			(end 0.120396 0.3048)
			(stroke
				(width 0.1)
				(type default)
			)
			(layer "F.Fab")
		)
		(pad "1" smd circle
			(at -0.40005 0)
			(size 0 0)
			(layers "F.Cu" "F.Mask" "F.Paste")
			(net "GPU_FPGA_RST_R1_BUF_N")
		)
		(pad "2" smd circle
			(at 0.40005 0)
			(size 0 0)
			(layers "F.Cu" "F.Mask" "F.Paste")
			(net "GPU_FPGA_RST_R_BUF_N")
		)
	)
	(footprint ""
		(layer "F.Cu")
		(at 124.107194 -402.371052 -90)
		(property "Reference" "C744"
			(at 0 0 270)
			(layer "F.SilkS")
			(hide yes)
			(effects
				(font
					(size 1.27 1.27)
				)
			)
		)
		(property "Value" ""
			(at 0 0 270)
			(layer "F.Fab")
			(effects
				(font
					(size 1.27 1.27)
				)
			)
		)
		(duplicate_pad_numbers_are_jumpers no)
		(fp_line
			(start -0.299974 0.150114)
			(end -0.299974 -0.150114)
			(stroke
				(width 0.1)
				(type default)
			)
			(layer "F.Fab")
		)
		(fp_line
			(start 0.299974 0.150114)
			(end -0.299974 0.150114)
			(stroke
				(width 0.1)
				(type default)
			)
			(layer "F.Fab")
		)
		(fp_line
			(start -0.299974 -0.150114)
			(end 0.299974 -0.150114)
			(stroke
				(width 0.1)
				(type default)
			)
			(layer "F.Fab")
		)
		(fp_line
			(start 0.299974 -0.150114)
			(end 0.299974 0.150114)
			(stroke
				(width 0.1)
				(type default)
			)
			(layer "F.Fab")
		)
		(pad "1" smd rect
			(at -0.2667 0 270)
			(size 0.3048 0.381)
			(layers "F.Cu" "F.Mask" "F.Paste")
			(net "P5E_CPU1_PE2_TX_C_DN<14>")
		)
		(pad "2" smd rect
			(at 0.2667 0 270)
			(size 0.3048 0.381)
			(layers "F.Cu" "F.Mask" "F.Paste")
			(net "P5E_CPU1_PE2_TX_DN<14>")
		)
	)
	(footprint ""
		(layer "F.Cu")
		(at 215.87714 -47.196248)
		(property "Reference" "R3586"
			(at 0 0 0)
			(layer "F.SilkS")
			(hide yes)
			(effects
				(font
					(size 1.27 1.27)
				)
			)
		)
		(property "Value" ""
			(at 0 0 0)
			(layer "F.Fab")
			(effects
				(font
					(size 1.27 1.27)
				)
			)
		)
		(duplicate_pad_numbers_are_jumpers no)
		(fp_line
			(start -0.7874 -0.4064)
			(end 0.7874 -0.4064)
			(stroke
				(width 0.1524)
				(type default)
			)
			(layer "F.SilkS")
		)
		(fp_line
			(start -0.7874 0.4064)
			(end -0.7874 -0.4064)
			(stroke
				(width 0.1524)
				(type default)
			)
			(layer "F.SilkS")
		)
		(fp_line
			(start 0.7874 -0.4064)
			(end 0.7874 0.4064)
			(stroke
				(width 0.1524)
				(type default)
			)
			(layer "F.SilkS")
		)
		(fp_line
			(start 0.7874 0.4064)
			(end -0.7874 0.4064)
			(stroke
				(width 0.1524)
				(type default)
			)
			(layer "F.SilkS")
		)
		(fp_line
			(start -0.67945 -0.305054)
			(end -0.12065 -0.305054)
			(stroke
				(width 0.1)
				(type default)
			)
			(layer "F.Fab")
		)
		(fp_line
			(start -0.67945 0.3048)
			(end -0.67945 -0.305054)
			(stroke
				(width 0.1)
				(type default)
			)
			(layer "F.Fab")
		)
		(fp_line
			(start -0.12065 -0.305054)
			(end -0.12065 -0.2794)
			(stroke
				(width 0.1)
				(type default)
			)
			(layer "F.Fab")
		)
		(fp_line
			(start -0.12065 -0.2794)
			(end 0.12065 -0.2794)
			(stroke
				(width 0.1)
				(type default)
			)
			(layer "F.Fab")
		)
		(fp_line
			(start -0.12065 0.2794)
			(end -0.12065 0.3048)
			(stroke
				(width 0.1)
				(type default)
			)
			(layer "F.Fab")
		)
		(fp_line
			(start -0.12065 0.3048)
			(end -0.67945 0.3048)
			(stroke
				(width 0.1)
				(type default)
			)
			(layer "F.Fab")
		)
		(fp_line
			(start 0.120396 0.2794)
			(end -0.12065 0.2794)
			(stroke
				(width 0.1)
				(type default)
			)
			(layer "F.Fab")
		)
		(fp_line
			(start 0.120396 0.3048)
			(end 0.120396 0.2794)
			(stroke
				(width 0.1)
				(type default)
			)
			(layer "F.Fab")
		)
		(fp_line
			(start 0.12065 -0.3048)
			(end 0.67945 -0.3048)
			(stroke
				(width 0.1)
				(type default)
			)
			(layer "F.Fab")
		)
		(fp_line
			(start 0.12065 -0.2794)
			(end 0.12065 -0.3048)
			(stroke
				(width 0.1)
				(type default)
			)
			(layer "F.Fab")
		)
		(fp_line
			(start 0.67945 -0.3048)
			(end 0.67945 0.3048)
			(stroke
				(width 0.1)
				(type default)
			)
			(layer "F.Fab")
		)
		(fp_line
			(start 0.67945 0.3048)
			(end 0.120396 0.3048)
			(stroke
				(width 0.1)
				(type default)
			)
			(layer "F.Fab")
		)
		(pad "1" smd circle
			(at -0.40005 0)
			(size 0 0)
			(layers "F.Cu" "F.Mask" "F.Paste")
			(net "SMB_INA230_3V3AUX_SCL")
		)
		(pad "2" smd circle
			(at 0.40005 0)
			(size 0 0)
			(layers "F.Cu" "F.Mask" "F.Paste")
			(net "SMB_INA230_1_3V3AUX_SCL_R")
		)
	)
	(footprint ""
		(layer "F.Cu")
		(at 166.01694 -30.584648)
		(property "Reference" "R4177"
			(at 0 0 0)
			(layer "F.SilkS")
			(hide yes)
			(effects
				(font
					(size 1.27 1.27)
				)
			)
		)
		(property "Value" ""
			(at 0 0 0)
			(layer "F.Fab")
			(effects
				(font
					(size 1.27 1.27)
				)
			)
		)
		(duplicate_pad_numbers_are_jumpers no)
		(fp_line
			(start -0.7874 -0.4064)
			(end 0.7874 -0.4064)
			(stroke
				(width 0.1524)
				(type default)
			)
			(layer "F.SilkS")
		)
		(fp_line
			(start -0.7874 0.4064)
			(end -0.7874 -0.4064)
			(stroke
				(width 0.1524)
				(type default)
			)
			(layer "F.SilkS")
		)
		(fp_line
			(start 0.7874 -0.4064)
			(end 0.7874 0.4064)
			(stroke
				(width 0.1524)
				(type default)
			)
			(layer "F.SilkS")
		)
		(fp_line
			(start 0.7874 0.4064)
			(end -0.7874 0.4064)
			(stroke
				(width 0.1524)
				(type default)
			)
			(layer "F.SilkS")
		)
		(fp_line
			(start -0.67945 -0.305054)
			(end -0.12065 -0.305054)
			(stroke
				(width 0.1)
				(type default)
			)
			(layer "F.Fab")
		)
		(fp_line
			(start -0.67945 0.3048)
			(end -0.67945 -0.305054)
			(stroke
				(width 0.1)
				(type default)
			)
			(layer "F.Fab")
		)
		(fp_line
			(start -0.12065 -0.305054)
			(end -0.12065 -0.2794)
			(stroke
				(width 0.1)
				(type default)
			)
			(layer "F.Fab")
		)
		(fp_line
			(start -0.12065 -0.2794)
			(end 0.12065 -0.2794)
			(stroke
				(width 0.1)
				(type default)
			)
			(layer "F.Fab")
		)
		(fp_line
			(start -0.12065 0.2794)
			(end -0.12065 0.3048)
			(stroke
				(width 0.1)
				(type default)
			)
			(layer "F.Fab")
		)
		(fp_line
			(start -0.12065 0.3048)
			(end -0.67945 0.3048)
			(stroke
				(width 0.1)
				(type default)
			)
			(layer "F.Fab")
		)
		(fp_line
			(start 0.120396 0.2794)
			(end -0.12065 0.2794)
			(stroke
				(width 0.1)
				(type default)
			)
			(layer "F.Fab")
		)
		(fp_line
			(start 0.120396 0.3048)
			(end 0.120396 0.2794)
			(stroke
				(width 0.1)
				(type default)
			)
			(layer "F.Fab")
		)
		(fp_line
			(start 0.12065 -0.3048)
			(end 0.67945 -0.3048)
			(stroke
				(width 0.1)
				(type default)
			)
			(layer "F.Fab")
		)
		(fp_line
			(start 0.12065 -0.2794)
			(end 0.12065 -0.3048)
			(stroke
				(width 0.1)
				(type default)
			)
			(layer "F.Fab")
		)
		(fp_line
			(start 0.67945 -0.3048)
			(end 0.67945 0.3048)
			(stroke
				(width 0.1)
				(type default)
			)
			(layer "F.Fab")
		)
		(fp_line
			(start 0.67945 0.3048)
			(end 0.120396 0.3048)
			(stroke
				(width 0.1)
				(type default)
			)
			(layer "F.Fab")
		)
		(pad "1" smd circle
			(at -0.40005 0)
			(size 0 0)
			(layers "F.Cu" "F.Mask" "F.Paste")
			(net "FM_ESPI_PLD_R_EN_BUF_R")
		)
		(pad "2" smd circle
			(at 0.40005 0)
			(size 0 0)
			(layers "F.Cu" "F.Mask" "F.Paste")
			(net "FM_ESPI_PLD_R_EN_BUF")
		)
	)
	(footprint ""
		(layer "F.Cu")
		(at 112.40008 -122.132598 90)
		(property "Reference" "R934"
			(at 0 0 90)
			(layer "F.SilkS")
			(hide yes)
			(effects
				(font
					(size 1.27 1.27)
				)
			)
		)
		(property "Value" ""
			(at 0 0 90)
			(layer "F.Fab")
			(effects
				(font
					(size 1.27 1.27)
				)
			)
		)
		(duplicate_pad_numbers_are_jumpers no)
		(fp_line
			(start 0.7874 -0.4064)
			(end 0.7874 0.4064)
			(stroke
				(width 0.1524)
				(type default)
			)
			(layer "F.SilkS")
		)
		(fp_line
			(start -0.7874 -0.4064)
			(end 0.7874 -0.4064)
			(stroke
				(width 0.1524)
				(type default)
			)
			(layer "F.SilkS")
		)
		(fp_line
			(start 0.7874 0.4064)
			(end -0.7874 0.4064)
			(stroke
				(width 0.1524)
				(type default)
			)
			(layer "F.SilkS")
		)
		(fp_line
			(start -0.7874 0.4064)
			(end -0.7874 -0.4064)
			(stroke
				(width 0.1524)
				(type default)
			)
			(layer "F.SilkS")
		)
		(fp_line
			(start -0.12065 -0.305054)
			(end -0.12065 -0.2794)
			(stroke
				(width 0.1)
				(type default)
			)
			(layer "F.Fab")
		)
		(fp_line
			(start -0.67945 -0.305054)
			(end -0.12065 -0.305054)
			(stroke
				(width 0.1)
				(type default)
			)
			(layer "F.Fab")
		)
		(fp_line
			(start 0.67945 -0.3048)
			(end 0.67945 0.3048)
			(stroke
				(width 0.1)
				(type default)
			)
			(layer "F.Fab")
		)
		(fp_line
			(start 0.12065 -0.3048)
			(end 0.67945 -0.3048)
			(stroke
				(width 0.1)
				(type default)
			)
			(layer "F.Fab")
		)
		(fp_line
			(start 0.12065 -0.2794)
			(end 0.12065 -0.3048)
			(stroke
				(width 0.1)
				(type default)
			)
			(layer "F.Fab")
		)
		(fp_line
			(start -0.12065 -0.2794)
			(end 0.12065 -0.2794)
			(stroke
				(width 0.1)
				(type default)
			)
			(layer "F.Fab")
		)
		(fp_line
			(start 0.120396 0.2794)
			(end -0.12065 0.2794)
			(stroke
				(width 0.1)
				(type default)
			)
			(layer "F.Fab")
		)
		(fp_line
			(start -0.12065 0.2794)
			(end -0.12065 0.3048)
			(stroke
				(width 0.1)
				(type default)
			)
			(layer "F.Fab")
		)
		(fp_line
			(start 0.67945 0.3048)
			(end 0.120396 0.3048)
			(stroke
				(width 0.1)
				(type default)
			)
			(layer "F.Fab")
		)
		(fp_line
			(start 0.120396 0.3048)
			(end 0.120396 0.2794)
			(stroke
				(width 0.1)
				(type default)
			)
			(layer "F.Fab")
		)
		(fp_line
			(start -0.12065 0.3048)
			(end -0.67945 0.3048)
			(stroke
				(width 0.1)
				(type default)
			)
			(layer "F.Fab")
		)
		(fp_line
			(start -0.67945 0.3048)
			(end -0.67945 -0.305054)
			(stroke
				(width 0.1)
				(type default)
			)
			(layer "F.Fab")
		)
		(pad "1" smd circle
			(at -0.40005 0 90)
			(size 0 0)
			(layers "F.Cu" "F.Mask" "F.Paste")
			(net "RST_CPU0_DRAM_CD_N")
		)
		(pad "2" smd circle
			(at 0.40005 0 90)
			(size 0 0)
			(layers "F.Cu" "F.Mask" "F.Paste")
			(net "GND")
		)
	)
)
